(kicad_pcb
	(version 20260206)
	(generator "pcbnew")
	(generator_version "10.0")
	(general
		(thickness 1.6)
		(legacy_teardrops no)
	)
	(paper "A4")
	(title_block
		(title "03242023_DA0F0TMBIJ0_F0T_Motherboard_J_brd_V01_OCP.brd")
		(comment 1 "Grand Teton / footprints 1149-1154 of 6105")
	)
	(layers
		(0 "F.Cu" signal "TOP")
		(4 "In1.Cu" signal "GND")
		(6 "In2.Cu" signal "IN1")
		(8 "In3.Cu" signal "GND1")
		(10 "In4.Cu" signal "IN2")
		(12 "In5.Cu" signal "GND2")
		(14 "In6.Cu" signal "IN3")
		(16 "In7.Cu" signal "GND3")
		(18 "In8.Cu" signal "VCC")
		(20 "In9.Cu" signal "VCC1")
		(22 "In10.Cu" signal "GND4")
		(24 "In11.Cu" signal "IN4")
		(26 "In12.Cu" signal "GND5")
		(28 "In13.Cu" signal "IN5")
		(30 "In14.Cu" signal "GND6")
		(32 "In15.Cu" signal "IN6")
		(34 "In16.Cu" signal "GND7")
		(2 "B.Cu" signal "BOTTOM")
		(9 "F.Adhes" user "F.Adhesive")
		(11 "B.Adhes" user "B.Adhesive")
		(13 "F.Paste" user "Package Geometry/Pastemask Top")
		(15 "B.Paste" user "Package Geometry/Pastemask Bottom")
		(5 "F.SilkS" user "Ref Des/Silkscreen Top")
		(7 "B.SilkS" user "Ref Des/Silkscreen Bottom")
		(1 "F.Mask" user "Board Geometry/Soldermask Top")
		(3 "B.Mask" user "Board Geometry/Soldermask Bottom")
		(17 "Dwgs.User" user "User.Drawings")
		(19 "Cmts.User" user "User.Comments")
		(21 "Eco1.User" user "User.Eco1")
		(23 "Eco2.User" user "User.Eco2")
		(25 "Edge.Cuts" user "Board Geometry/Outline")
		(27 "Margin" user)
		(31 "F.CrtYd" user "Package Geometry/Place Bound Top")
		(29 "B.CrtYd" user "Package Geometry/Place Bound Bottom")
		(35 "F.Fab" user "Ref Des/Assembly Top")
		(33 "B.Fab" user "Ref Des/Assembly Bottom")
	)
	(footprint ""
		(layer "F.Cu")
		(at 353.245928 -260.364986 -90)
		(property "Reference" "C409"
			(at 0 0 270)
			(layer "F.SilkS")
			(hide yes)
			(effects
				(font
					(size 1.27 1.27)
				)
			)
		)
		(property "Value" ""
			(at 0 0 270)
			(layer "F.Fab")
			(effects
				(font
					(size 1.27 1.27)
				)
			)
		)
		(duplicate_pad_numbers_are_jumpers no)
		(fp_line
			(start -0.7874 0.4064)
			(end -0.7874 -0.4064)
			(stroke
				(width 0.1524)
				(type default)
			)
			(layer "F.SilkS")
		)
		(fp_line
			(start 0.7874 0.4064)
			(end -0.7874 0.4064)
			(stroke
				(width 0.1524)
				(type default)
			)
			(layer "F.SilkS")
		)
		(fp_line
			(start -0.7874 -0.4064)
			(end 0.7874 -0.4064)
			(stroke
				(width 0.1524)
				(type default)
			)
			(layer "F.SilkS")
		)
		(fp_line
			(start 0.7874 -0.4064)
			(end 0.7874 0.4064)
			(stroke
				(width 0.1524)
				(type default)
			)
			(layer "F.SilkS")
		)
		(fp_line
			(start -0.67945 0.3048)
			(end -0.67945 -0.305054)
			(stroke
				(width 0.1)
				(type default)
			)
			(layer "F.Fab")
		)
		(fp_line
			(start -0.12065 0.3048)
			(end -0.67945 0.3048)
			(stroke
				(width 0.1)
				(type default)
			)
			(layer "F.Fab")
		)
		(fp_line
			(start 0.120396 0.3048)
			(end 0.120396 0.2794)
			(stroke
				(width 0.1)
				(type default)
			)
			(layer "F.Fab")
		)
		(fp_line
			(start 0.67945 0.3048)
			(end 0.120396 0.3048)
			(stroke
				(width 0.1)
				(type default)
			)
			(layer "F.Fab")
		)
		(fp_line
			(start -0.12065 0.2794)
			(end -0.12065 0.3048)
			(stroke
				(width 0.1)
				(type default)
			)
			(layer "F.Fab")
		)
		(fp_line
			(start 0.120396 0.2794)
			(end -0.12065 0.2794)
			(stroke
				(width 0.1)
				(type default)
			)
			(layer "F.Fab")
		)
		(fp_line
			(start -0.12065 -0.2794)
			(end 0.12065 -0.2794)
			(stroke
				(width 0.1)
				(type default)
			)
			(layer "F.Fab")
		)
		(fp_line
			(start 0.12065 -0.2794)
			(end 0.12065 -0.3048)
			(stroke
				(width 0.1)
				(type default)
			)
			(layer "F.Fab")
		)
		(fp_line
			(start 0.12065 -0.3048)
			(end 0.67945 -0.3048)
			(stroke
				(width 0.1)
				(type default)
			)
			(layer "F.Fab")
		)
		(fp_line
			(start 0.67945 -0.3048)
			(end 0.67945 0.3048)
			(stroke
				(width 0.1)
				(type default)
			)
			(layer "F.Fab")
		)
		(fp_line
			(start -0.67945 -0.305054)
			(end -0.12065 -0.305054)
			(stroke
				(width 0.1)
				(type default)
			)
			(layer "F.Fab")
		)
		(fp_line
			(start -0.12065 -0.305054)
			(end -0.12065 -0.2794)
			(stroke
				(width 0.1)
				(type default)
			)
			(layer "F.Fab")
		)
		(pad "1" smd circle
			(at -0.40005 0 270)
			(size 0 0)
			(layers "F.Cu" "F.Mask" "F.Paste")
			(net "PVCCFA_EHV_FIVRA_CPU0")
		)
		(pad "2" smd circle
			(at 0.40005 0 270)
			(size 0 0)
			(layers "F.Cu" "F.Mask" "F.Paste")
			(net "GND")
		)
	)
	(footprint ""
		(layer "F.Cu")
		(at 369.358418 -417.17341 90)
		(property "Reference" "R4190"
			(at 0 0 90)
			(layer "F.SilkS")
			(hide yes)
			(effects
				(font
					(size 1.27 1.27)
				)
			)
		)
		(property "Value" ""
			(at 0 0 90)
			(layer "F.Fab")
			(effects
				(font
					(size 1.27 1.27)
				)
			)
		)
		(duplicate_pad_numbers_are_jumpers no)
		(fp_line
			(start 0.7874 -0.4064)
			(end 0.7874 0.4064)
			(stroke
				(width 0.1524)
				(type default)
			)
			(layer "F.SilkS")
		)
		(fp_line
			(start -0.7874 -0.4064)
			(end 0.7874 -0.4064)
			(stroke
				(width 0.1524)
				(type default)
			)
			(layer "F.SilkS")
		)
		(fp_line
			(start 0.7874 0.4064)
			(end -0.7874 0.4064)
			(stroke
				(width 0.1524)
				(type default)
			)
			(layer "F.SilkS")
		)
		(fp_line
			(start -0.7874 0.4064)
			(end -0.7874 -0.4064)
			(stroke
				(width 0.1524)
				(type default)
			)
			(layer "F.SilkS")
		)
		(fp_line
			(start -0.12065 -0.305054)
			(end -0.12065 -0.2794)
			(stroke
				(width 0.1)
				(type default)
			)
			(layer "F.Fab")
		)
		(fp_line
			(start -0.67945 -0.305054)
			(end -0.12065 -0.305054)
			(stroke
				(width 0.1)
				(type default)
			)
			(layer "F.Fab")
		)
		(fp_line
			(start 0.67945 -0.3048)
			(end 0.67945 0.3048)
			(stroke
				(width 0.1)
				(type default)
			)
			(layer "F.Fab")
		)
		(fp_line
			(start 0.12065 -0.3048)
			(end 0.67945 -0.3048)
			(stroke
				(width 0.1)
				(type default)
			)
			(layer "F.Fab")
		)
		(fp_line
			(start 0.12065 -0.2794)
			(end 0.12065 -0.3048)
			(stroke
				(width 0.1)
				(type default)
			)
			(layer "F.Fab")
		)
		(fp_line
			(start -0.12065 -0.2794)
			(end 0.12065 -0.2794)
			(stroke
				(width 0.1)
				(type default)
			)
			(layer "F.Fab")
		)
		(fp_line
			(start 0.120396 0.2794)
			(end -0.12065 0.2794)
			(stroke
				(width 0.1)
				(type default)
			)
			(layer "F.Fab")
		)
		(fp_line
			(start -0.12065 0.2794)
			(end -0.12065 0.3048)
			(stroke
				(width 0.1)
				(type default)
			)
			(layer "F.Fab")
		)
		(fp_line
			(start 0.67945 0.3048)
			(end 0.120396 0.3048)
			(stroke
				(width 0.1)
				(type default)
			)
			(layer "F.Fab")
		)
		(fp_line
			(start 0.120396 0.3048)
			(end 0.120396 0.2794)
			(stroke
				(width 0.1)
				(type default)
			)
			(layer "F.Fab")
		)
		(fp_line
			(start -0.12065 0.3048)
			(end -0.67945 0.3048)
			(stroke
				(width 0.1)
				(type default)
			)
			(layer "F.Fab")
		)
		(fp_line
			(start -0.67945 0.3048)
			(end -0.67945 -0.305054)
			(stroke
				(width 0.1)
				(type default)
			)
			(layer "F.Fab")
		)
		(pad "1" smd circle
			(at -0.40005 0 90)
			(size 0 0)
			(layers "F.Cu" "F.Mask" "F.Paste")
			(net "P3V3_AUX")
		)
		(pad "2" smd circle
			(at 0.40005 0 90)
			(size 0 0)
			(layers "F.Cu" "F.Mask" "F.Paste")
			(net "U270_0_ADD2")
		)
	)
	(footprint ""
		(layer "F.Cu")
		(at 306.263294 -14.51102)
		(property "Reference" "R2487"
			(at 0 0 0)
			(layer "F.SilkS")
			(hide yes)
			(effects
				(font
					(size 1.27 1.27)
				)
			)
		)
		(property "Value" ""
			(at 0 0 0)
			(layer "F.Fab")
			(effects
				(font
					(size 1.27 1.27)
				)
			)
		)
		(duplicate_pad_numbers_are_jumpers no)
		(fp_line
			(start -0.7874 -0.4064)
			(end 0.7874 -0.4064)
			(stroke
				(width 0.1524)
				(type default)
			)
			(layer "F.SilkS")
		)
		(fp_line
			(start -0.7874 0.4064)
			(end -0.7874 -0.4064)
			(stroke
				(width 0.1524)
				(type default)
			)
			(layer "F.SilkS")
		)
		(fp_line
			(start 0.7874 -0.4064)
			(end 0.7874 0.4064)
			(stroke
				(width 0.1524)
				(type default)
			)
			(layer "F.SilkS")
		)
		(fp_line
			(start 0.7874 0.4064)
			(end -0.7874 0.4064)
			(stroke
				(width 0.1524)
				(type default)
			)
			(layer "F.SilkS")
		)
		(fp_line
			(start -0.67945 -0.305054)
			(end -0.12065 -0.305054)
			(stroke
				(width 0.1)
				(type default)
			)
			(layer "F.Fab")
		)
		(fp_line
			(start -0.67945 0.3048)
			(end -0.67945 -0.305054)
			(stroke
				(width 0.1)
				(type default)
			)
			(layer "F.Fab")
		)
		(fp_line
			(start -0.12065 -0.305054)
			(end -0.12065 -0.2794)
			(stroke
				(width 0.1)
				(type default)
			)
			(layer "F.Fab")
		)
		(fp_line
			(start -0.12065 -0.2794)
			(end 0.12065 -0.2794)
			(stroke
				(width 0.1)
				(type default)
			)
			(layer "F.Fab")
		)
		(fp_line
			(start -0.12065 0.2794)
			(end -0.12065 0.3048)
			(stroke
				(width 0.1)
				(type default)
			)
			(layer "F.Fab")
		)
		(fp_line
			(start -0.12065 0.3048)
			(end -0.67945 0.3048)
			(stroke
				(width 0.1)
				(type default)
			)
			(layer "F.Fab")
		)
		(fp_line
			(start 0.120396 0.2794)
			(end -0.12065 0.2794)
			(stroke
				(width 0.1)
				(type default)
			)
			(layer "F.Fab")
		)
		(fp_line
			(start 0.120396 0.3048)
			(end 0.120396 0.2794)
			(stroke
				(width 0.1)
				(type default)
			)
			(layer "F.Fab")
		)
		(fp_line
			(start 0.12065 -0.3048)
			(end 0.67945 -0.3048)
			(stroke
				(width 0.1)
				(type default)
			)
			(layer "F.Fab")
		)
		(fp_line
			(start 0.12065 -0.2794)
			(end 0.12065 -0.3048)
			(stroke
				(width 0.1)
				(type default)
			)
			(layer "F.Fab")
		)
		(fp_line
			(start 0.67945 -0.3048)
			(end 0.67945 0.3048)
			(stroke
				(width 0.1)
				(type default)
			)
			(layer "F.Fab")
		)
		(fp_line
			(start 0.67945 0.3048)
			(end 0.120396 0.3048)
			(stroke
				(width 0.1)
				(type default)
			)
			(layer "F.Fab")
		)
		(pad "1" smd circle
			(at -0.40005 0)
			(size 0 0)
			(layers "F.Cu" "F.Mask" "F.Paste")
			(net "P3V3_AUX")
		)
		(pad "2" smd circle
			(at 0.40005 0)
			(size 0 0)
			(layers "F.Cu" "F.Mask" "F.Paste")
			(net "IRQ_LVC3_WAKE_BUF_N")
		)
	)
	(footprint ""
		(layer "F.Cu")
		(at 155.194 -126.365 -90)
		(property "Reference" "R4638"
			(at 0 0 270)
			(layer "F.SilkS")
			(hide yes)
			(effects
				(font
					(size 1.27 1.27)
				)
			)
		)
		(property "Value" ""
			(at 0 0 270)
			(layer "F.Fab")
			(effects
				(font
					(size 1.27 1.27)
				)
			)
		)
		(duplicate_pad_numbers_are_jumpers no)
		(fp_line
			(start -2.234946 0.9271)
			(end -2.234946 -0.9271)
			(stroke
				(width 0.1524)
				(type default)
			)
			(layer "F.SilkS")
		)
		(fp_line
			(start 2.234946 0.9271)
			(end -2.234946 0.9271)
			(stroke
				(width 0.1524)
				(type default)
			)
			(layer "F.SilkS")
		)
		(fp_line
			(start -2.234946 -0.9271)
			(end 2.234946 -0.9271)
			(stroke
				(width 0.1524)
				(type default)
			)
			(layer "F.SilkS")
		)
		(fp_line
			(start 2.234946 -0.9271)
			(end 2.234946 0.9271)
			(stroke
				(width 0.1524)
				(type default)
			)
			(layer "F.SilkS")
		)
		(fp_line
			(start -1.575054 0.824992)
			(end 1.575054 0.824992)
			(stroke
				(width 0.1)
				(type default)
			)
			(layer "F.Fab")
		)
		(fp_line
			(start 1.575054 0.824992)
			(end 1.575054 -0.824992)
			(stroke
				(width 0.1)
				(type default)
			)
			(layer "F.Fab")
		)
		(fp_line
			(start -1.575054 -0.824992)
			(end -1.575054 0.824992)
			(stroke
				(width 0.1)
				(type default)
			)
			(layer "F.Fab")
		)
		(fp_line
			(start 1.575054 -0.824992)
			(end -1.575054 -0.824992)
			(stroke
				(width 0.1)
				(type default)
			)
			(layer "F.Fab")
		)
		(pad "1" smd rect
			(at -1.599946 0 270)
			(size 1.016 1.6002)
			(layers "F.Cu" "F.Mask" "F.Paste")
			(net "P5V")
		)
		(pad "2" smd rect
			(at 1.599946 0 270)
			(size 1.016 1.6002)
			(layers "F.Cu" "F.Mask" "F.Paste")
			(net "VR_P5V_EN_D")
		)
	)
	(footprint ""
		(layer "F.Cu")
		(at 129.69748 -327.79335)
		(property "Reference" "PL27"
			(at 4.329684 4.104894 0)
			(unlocked yes)
			(layer "F.SilkS")
			(effects
				(font
					(size 0.7874 0.5842)
					(thickness 0.1524)
				)
				(justify left)
			)
		)
		(property "Value" ""
			(at 0 0 0)
			(layer "F.Fab")
			(effects
				(font
					(size 1.27 1.27)
				)
			)
		)
		(duplicate_pad_numbers_are_jumpers no)
		(fp_line
			(start -3.750056 -5.500116)
			(end -2.393442 -5.500116)
			(stroke
				(width 0.1524)
				(type default)
			)
			(layer "F.SilkS")
		)
		(fp_line
			(start -3.750056 5.500116)
			(end -3.750056 -5.500116)
			(stroke
				(width 0.1524)
				(type default)
			)
			(layer "F.SilkS")
		)
		(fp_line
			(start -2.393442 5.500116)
			(end -3.750056 5.500116)
			(stroke
				(width 0.1524)
				(type default)
			)
			(layer "F.SilkS")
		)
		(fp_line
			(start 2.393442 5.500116)
			(end 3.750056 5.500116)
			(stroke
				(width 0.1524)
				(type default)
			)
			(layer "F.SilkS")
		)
		(fp_line
			(start 3.750056 -5.500116)
			(end 2.393442 -5.500116)
			(stroke
				(width 0.1524)
				(type default)
			)
			(layer "F.SilkS")
		)
		(fp_line
			(start 3.750056 5.500116)
			(end 3.750056 -5.500116)
			(stroke
				(width 0.1524)
				(type default)
			)
			(layer "F.SilkS")
		)
		(fp_poly
			(pts
				(xy -5.12318 -4.930648) (xy -4.10718 -4.422648) (xy -5.12318 -3.914648)
			)
			(stroke
				(width 0)
				(type default)
			)
			(fill yes)
			(layer "F.SilkS")
		)
		(fp_line
			(start -3.750056 -5.500116)
			(end -3.750056 5.500116)
			(stroke
				(width 0.1)
				(type default)
			)
			(layer "F.Fab")
		)
		(fp_line
			(start -3.750056 5.500116)
			(end 3.750056 5.500116)
			(stroke
				(width 0.1)
				(type default)
			)
			(layer "F.Fab")
		)
		(fp_line
			(start 3.750056 -5.500116)
			(end -3.750056 -5.500116)
			(stroke
				(width 0.1)
				(type default)
			)
			(layer "F.Fab")
		)
		(fp_line
			(start 3.750056 5.500116)
			(end 3.750056 -5.500116)
			(stroke
				(width 0.1)
				(type default)
			)
			(layer "F.Fab")
		)
		(fp_poly
			(pts
				(xy -4.9276 -4.757928) (xy -4.9276 -3.741928) (xy -3.9116 -4.249928)
			)
			(stroke
				(width 0)
				(type default)
			)
			(fill yes)
			(layer "F.Fab")
		)
		(pad "1" smd rect
			(at 0 -4.249928 270)
			(size 2.413 4.5212)
			(layers "F.Cu" "F.Mask" "F.Paste")
			(net "SW_PVCCIN_CPU1_SW5")
		)
		(pad "2" smd rect
			(at 0 -1.175004 270)
			(size 1.3716 4.5212)
			(layers "F.Cu" "F.Mask" "F.Paste")
			(net "IND_P1_CPL5")
		)
		(pad "3" smd rect
			(at 0 1.175004 270)
			(size 1.3716 4.5212)
			(layers "F.Cu" "F.Mask" "F.Paste")
			(net "IND_P1_CPL4")
		)
		(pad "4" smd rect
			(at 0 4.249928 270)
			(size 2.413 4.5212)
			(layers "F.Cu" "F.Mask" "F.Paste")
			(net "PVCCIN_CPU1")
		)
	)
	(footprint ""
		(layer "F.Cu")
		(at 140.00988 -43.652948 180)
		(property "Reference" "R3296"
			(at 0 0 180)
			(layer "F.SilkS")
			(hide yes)
			(effects
				(font
					(size 1.27 1.27)
				)
			)
		)
		(property "Value" ""
			(at 0 0 180)
			(layer "F.Fab")
			(effects
				(font
					(size 1.27 1.27)
				)
			)
		)
		(duplicate_pad_numbers_are_jumpers no)
		(fp_line
			(start 0.7874 0.4064)
			(end -0.7874 0.4064)
			(stroke
				(width 0.1524)
				(type default)
			)
			(layer "F.SilkS")
		)
		(fp_line
			(start 0.7874 -0.4064)
			(end 0.7874 0.4064)
			(stroke
				(width 0.1524)
				(type default)
			)
			(layer "F.SilkS")
		)
		(fp_line
			(start -0.7874 0.4064)
			(end -0.7874 -0.4064)
			(stroke
				(width 0.1524)
				(type default)
			)
			(layer "F.SilkS")
		)
		(fp_line
			(start -0.7874 -0.4064)
			(end 0.7874 -0.4064)
			(stroke
				(width 0.1524)
				(type default)
			)
			(layer "F.SilkS")
		)
		(fp_line
			(start 0.67945 0.3048)
			(end 0.120396 0.3048)
			(stroke
				(width 0.1)
				(type default)
			)
			(layer "F.Fab")
		)
		(fp_line
			(start 0.67945 -0.3048)
			(end 0.67945 0.3048)
			(stroke
				(width 0.1)
				(type default)
			)
			(layer "F.Fab")
		)
		(fp_line
			(start 0.12065 -0.2794)
			(end 0.12065 -0.3048)
			(stroke
				(width 0.1)
				(type default)
			)
			(layer "F.Fab")
		)
		(fp_line
			(start 0.12065 -0.3048)
			(end 0.67945 -0.3048)
			(stroke
				(width 0.1)
				(type default)
			)
			(layer "F.Fab")
		)
		(fp_line
			(start 0.120396 0.3048)
			(end 0.120396 0.2794)
			(stroke
				(width 0.1)
				(type default)
			)
			(layer "F.Fab")
		)
		(fp_line
			(start 0.120396 0.2794)
			(end -0.12065 0.2794)
			(stroke
				(width 0.1)
				(type default)
			)
			(layer "F.Fab")
		)
		(fp_line
			(start -0.12065 0.3048)
			(end -0.67945 0.3048)
			(stroke
				(width 0.1)
				(type default)
			)
			(layer "F.Fab")
		)
		(fp_line
			(start -0.12065 0.2794)
			(end -0.12065 0.3048)
			(stroke
				(width 0.1)
				(type default)
			)
			(layer "F.Fab")
		)
		(fp_line
			(start -0.12065 -0.2794)
			(end 0.12065 -0.2794)
			(stroke
				(width 0.1)
				(type default)
			)
			(layer "F.Fab")
		)
		(fp_line
			(start -0.12065 -0.305054)
			(end -0.12065 -0.2794)
			(stroke
				(width 0.1)
				(type default)
			)
			(layer "F.Fab")
		)
		(fp_line
			(start -0.67945 0.3048)
			(end -0.67945 -0.305054)
			(stroke
				(width 0.1)
				(type default)
			)
			(layer "F.Fab")
		)
		(fp_line
			(start -0.67945 -0.305054)
			(end -0.12065 -0.305054)
			(stroke
				(width 0.1)
				(type default)
			)
			(layer "F.Fab")
		)
		(pad "1" smd circle
			(at -0.40005 0 180)
			(size 0 0)
			(layers "F.Cu" "F.Mask" "F.Paste")
			(net "P3V3_AUX")
		)
		(pad "2" smd circle
			(at 0.40005 0 180)
			(size 0 0)
			(layers "F.Cu" "F.Mask" "F.Paste")
			(net "HDD_ACTIVITY_BUF")
		)
	)
)
